(kicad_pcb
	(version 20260206)
	(generator "pcbnew")
	(generator_version "10.0")
	(general
		(thickness 1.6)
		(legacy_teardrops no)
	)
	(paper "A4")
	(title_block
		(title "04192023_DAF0TMB3IC0_F0TG_MB_C_brd_V02_OCP.brd")
		(comment 1 "Grand Teton / footprints 846-851 of 8354")
	)
	(layers
		(0 "F.Cu" signal "TOP")
		(4 "In1.Cu" signal "GND")
		(6 "In2.Cu" signal "IN1")
		(8 "In3.Cu" signal "GND1")
		(10 "In4.Cu" signal "IN2")
		(12 "In5.Cu" signal "GND2")
		(14 "In6.Cu" signal "IN3")
		(16 "In7.Cu" signal "GND3")
		(18 "In8.Cu" signal "VCC")
		(20 "In9.Cu" signal "VCC1")
		(22 "In10.Cu" signal "GND4")
		(24 "In11.Cu" signal "IN4")
		(26 "In12.Cu" signal "GND5")
		(28 "In13.Cu" signal "IN5")
		(30 "In14.Cu" signal "GND6")
		(32 "In15.Cu" signal "IN6")
		(34 "In16.Cu" signal "GND7")
		(2 "B.Cu" signal "BOTTOM")
		(9 "F.Adhes" user "F.Adhesive")
		(11 "B.Adhes" user "B.Adhesive")
		(13 "F.Paste" user "Package Geometry/Pastemask Top")
		(15 "B.Paste" user "Package Geometry/Pastemask Bottom")
		(5 "F.SilkS" user "Ref Des/Silkscreen Top")
		(7 "B.SilkS" user "Ref Des/Silkscreen Bottom")
		(1 "F.Mask" user "Board Geometry/Soldermask Top")
		(3 "B.Mask" user "Board Geometry/Soldermask Bottom")
		(17 "Dwgs.User" user "User.Drawings")
		(19 "Cmts.User" user "User.Comments")
		(21 "Eco1.User" user "User.Eco1")
		(23 "Eco2.User" user "User.Eco2")
		(25 "Edge.Cuts" user "Board Geometry/Outline")
		(27 "Margin" user)
		(31 "F.CrtYd" user "Package Geometry/Place Bound Top")
		(29 "B.CrtYd" user "Package Geometry/Place Bound Bottom")
		(35 "F.Fab" user "Ref Des/Assembly Top")
		(33 "B.Fab" user "Ref Des/Assembly Bottom")
	)
	(footprint ""
		(layer "F.Cu")
		(at 171.204128 -123.683268 180)
		(property "Reference" "R6143"
			(at 0 0 180)
			(layer "F.SilkS")
			(hide yes)
			(effects
				(font
					(size 1.27 1.27)
				)
			)
		)
		(property "Value" ""
			(at 0 0 180)
			(layer "F.Fab")
			(effects
				(font
					(size 1.27 1.27)
				)
			)
		)
		(duplicate_pad_numbers_are_jumpers no)
		(fp_line
			(start 0.7874 0.4064)
			(end -0.7874 0.4064)
			(stroke
				(width 0.1524)
				(type default)
			)
			(layer "F.SilkS")
		)
		(fp_line
			(start 0.7874 -0.4064)
			(end 0.7874 0.4064)
			(stroke
				(width 0.1524)
				(type default)
			)
			(layer "F.SilkS")
		)
		(fp_line
			(start -0.7874 0.4064)
			(end -0.7874 -0.4064)
			(stroke
				(width 0.1524)
				(type default)
			)
			(layer "F.SilkS")
		)
		(fp_line
			(start -0.7874 -0.4064)
			(end 0.7874 -0.4064)
			(stroke
				(width 0.1524)
				(type default)
			)
			(layer "F.SilkS")
		)
		(fp_line
			(start 0.67945 0.3048)
			(end 0.120396 0.3048)
			(stroke
				(width 0.1)
				(type default)
			)
			(layer "F.Fab")
		)
		(fp_line
			(start 0.67945 -0.3048)
			(end 0.67945 0.3048)
			(stroke
				(width 0.1)
				(type default)
			)
			(layer "F.Fab")
		)
		(fp_line
			(start 0.12065 -0.2794)
			(end 0.12065 -0.3048)
			(stroke
				(width 0.1)
				(type default)
			)
			(layer "F.Fab")
		)
		(fp_line
			(start 0.12065 -0.3048)
			(end 0.67945 -0.3048)
			(stroke
				(width 0.1)
				(type default)
			)
			(layer "F.Fab")
		)
		(fp_line
			(start 0.120396 0.3048)
			(end 0.120396 0.2794)
			(stroke
				(width 0.1)
				(type default)
			)
			(layer "F.Fab")
		)
		(fp_line
			(start 0.120396 0.2794)
			(end -0.12065 0.2794)
			(stroke
				(width 0.1)
				(type default)
			)
			(layer "F.Fab")
		)
		(fp_line
			(start -0.12065 0.3048)
			(end -0.67945 0.3048)
			(stroke
				(width 0.1)
				(type default)
			)
			(layer "F.Fab")
		)
		(fp_line
			(start -0.12065 0.2794)
			(end -0.12065 0.3048)
			(stroke
				(width 0.1)
				(type default)
			)
			(layer "F.Fab")
		)
		(fp_line
			(start -0.12065 -0.2794)
			(end 0.12065 -0.2794)
			(stroke
				(width 0.1)
				(type default)
			)
			(layer "F.Fab")
		)
		(fp_line
			(start -0.12065 -0.305054)
			(end -0.12065 -0.2794)
			(stroke
				(width 0.1)
				(type default)
			)
			(layer "F.Fab")
		)
		(fp_line
			(start -0.67945 0.3048)
			(end -0.67945 -0.305054)
			(stroke
				(width 0.1)
				(type default)
			)
			(layer "F.Fab")
		)
		(fp_line
			(start -0.67945 -0.305054)
			(end -0.12065 -0.305054)
			(stroke
				(width 0.1)
				(type default)
			)
			(layer "F.Fab")
		)
		(pad "1" smd circle
			(at -0.40005 0 180)
			(size 0 0)
			(layers "F.Cu" "F.Mask" "F.Paste")
			(net "FM_BOARD_BMC_SKU_ID2")
		)
		(pad "2" smd circle
			(at 0.40005 0 180)
			(size 0 0)
			(layers "F.Cu" "F.Mask" "F.Paste")
			(net "GND")
		)
	)
	(footprint ""
		(layer "F.Cu")
		(at 115.70589 -258.795266)
		(property "Reference" "C2428"
			(at 0 0 0)
			(layer "F.SilkS")
			(hide yes)
			(effects
				(font
					(size 1.27 1.27)
				)
			)
		)
		(property "Value" ""
			(at 0 0 0)
			(layer "F.Fab")
			(effects
				(font
					(size 1.27 1.27)
				)
			)
		)
		(duplicate_pad_numbers_are_jumpers no)
		(fp_line
			(start -0.7874 -0.4064)
			(end 0.7874 -0.4064)
			(stroke
				(width 0.1524)
				(type default)
			)
			(layer "F.SilkS")
		)
		(fp_line
			(start -0.7874 0.4064)
			(end -0.7874 -0.4064)
			(stroke
				(width 0.1524)
				(type default)
			)
			(layer "F.SilkS")
		)
		(fp_line
			(start 0.7874 -0.4064)
			(end 0.7874 0.4064)
			(stroke
				(width 0.1524)
				(type default)
			)
			(layer "F.SilkS")
		)
		(fp_line
			(start 0.7874 0.4064)
			(end -0.7874 0.4064)
			(stroke
				(width 0.1524)
				(type default)
			)
			(layer "F.SilkS")
		)
		(fp_line
			(start -0.67945 -0.305054)
			(end -0.12065 -0.305054)
			(stroke
				(width 0.1)
				(type default)
			)
			(layer "F.Fab")
		)
		(fp_line
			(start -0.67945 0.3048)
			(end -0.67945 -0.305054)
			(stroke
				(width 0.1)
				(type default)
			)
			(layer "F.Fab")
		)
		(fp_line
			(start -0.12065 -0.305054)
			(end -0.12065 -0.2794)
			(stroke
				(width 0.1)
				(type default)
			)
			(layer "F.Fab")
		)
		(fp_line
			(start -0.12065 -0.2794)
			(end 0.12065 -0.2794)
			(stroke
				(width 0.1)
				(type default)
			)
			(layer "F.Fab")
		)
		(fp_line
			(start -0.12065 0.2794)
			(end -0.12065 0.3048)
			(stroke
				(width 0.1)
				(type default)
			)
			(layer "F.Fab")
		)
		(fp_line
			(start -0.12065 0.3048)
			(end -0.67945 0.3048)
			(stroke
				(width 0.1)
				(type default)
			)
			(layer "F.Fab")
		)
		(fp_line
			(start 0.120396 0.2794)
			(end -0.12065 0.2794)
			(stroke
				(width 0.1)
				(type default)
			)
			(layer "F.Fab")
		)
		(fp_line
			(start 0.120396 0.3048)
			(end 0.120396 0.2794)
			(stroke
				(width 0.1)
				(type default)
			)
			(layer "F.Fab")
		)
		(fp_line
			(start 0.12065 -0.3048)
			(end 0.67945 -0.3048)
			(stroke
				(width 0.1)
				(type default)
			)
			(layer "F.Fab")
		)
		(fp_line
			(start 0.12065 -0.2794)
			(end 0.12065 -0.3048)
			(stroke
				(width 0.1)
				(type default)
			)
			(layer "F.Fab")
		)
		(fp_line
			(start 0.67945 -0.3048)
			(end 0.67945 0.3048)
			(stroke
				(width 0.1)
				(type default)
			)
			(layer "F.Fab")
		)
		(fp_line
			(start 0.67945 0.3048)
			(end 0.120396 0.3048)
			(stroke
				(width 0.1)
				(type default)
			)
			(layer "F.Fab")
		)
		(pad "1" smd circle
			(at -0.40005 0)
			(size 0 0)
			(layers "F.Cu" "F.Mask" "F.Paste")
			(net "PVDDCR_SOC_P1")
		)
		(pad "2" smd circle
			(at 0.40005 0)
			(size 0 0)
			(layers "F.Cu" "F.Mask" "F.Paste")
			(net "GND")
		)
	)
	(footprint ""
		(layer "F.Cu")
		(at 197.610476 -358.027478)
		(property "Reference" "PC8007"
			(at 0 0 0)
			(layer "F.SilkS")
			(hide yes)
			(effects
				(font
					(size 1.27 1.27)
				)
			)
		)
		(property "Value" ""
			(at 0 0 0)
			(layer "F.Fab")
			(effects
				(font
					(size 1.27 1.27)
				)
			)
		)
		(duplicate_pad_numbers_are_jumpers no)
		(fp_line
			(start -1.524 -0.762)
			(end 1.524 -0.762)
			(stroke
				(width 0.1524)
				(type default)
			)
			(layer "F.SilkS")
		)
		(fp_line
			(start -1.524 0.762)
			(end -1.524 -0.762)
			(stroke
				(width 0.1524)
				(type default)
			)
			(layer "F.SilkS")
		)
		(fp_line
			(start 1.524 -0.762)
			(end 1.524 0.762)
			(stroke
				(width 0.1524)
				(type default)
			)
			(layer "F.SilkS")
		)
		(fp_line
			(start 1.524 0.762)
			(end -1.524 0.762)
			(stroke
				(width 0.1524)
				(type default)
			)
			(layer "F.SilkS")
		)
		(fp_line
			(start -1.1049 -0.724916)
			(end -1.1049 0.724916)
			(stroke
				(width 0.1)
				(type default)
			)
			(layer "F.Fab")
		)
		(fp_line
			(start -1.1049 0.724916)
			(end 1.1049 0.724916)
			(stroke
				(width 0.1)
				(type default)
			)
			(layer "F.Fab")
		)
		(fp_line
			(start 1.1049 -0.724916)
			(end -1.1049 -0.724916)
			(stroke
				(width 0.1)
				(type default)
			)
			(layer "F.Fab")
		)
		(fp_line
			(start 1.1049 0.724916)
			(end 1.1049 -0.724916)
			(stroke
				(width 0.1)
				(type default)
			)
			(layer "F.Fab")
		)
		(pad "1" smd rect
			(at -0.889 0 180)
			(size 1.016 1.27)
			(layers "F.Cu" "F.Mask" "F.Paste")
			(net "SW_P12V_AUX_PVDD11_S3_P1_FLT")
		)
		(pad "2" smd rect
			(at 0.889 0 180)
			(size 1.016 1.27)
			(layers "F.Cu" "F.Mask" "F.Paste")
			(net "GND")
		)
	)
	(footprint ""
		(layer "F.Cu")
		(at 330.938632 -410.251656 90)
		(property "Reference" "C7035"
			(at 0 0 90)
			(layer "F.SilkS")
			(hide yes)
			(effects
				(font
					(size 1.27 1.27)
				)
			)
		)
		(property "Value" ""
			(at 0 0 90)
			(layer "F.Fab")
			(effects
				(font
					(size 1.27 1.27)
				)
			)
		)
		(duplicate_pad_numbers_are_jumpers no)
		(fp_line
			(start 1.524 -0.762)
			(end 1.524 0.762)
			(stroke
				(width 0.1524)
				(type default)
			)
			(layer "F.SilkS")
		)
		(fp_line
			(start -1.524 -0.762)
			(end 1.524 -0.762)
			(stroke
				(width 0.1524)
				(type default)
			)
			(layer "F.SilkS")
		)
		(fp_line
			(start 1.524 0.762)
			(end -1.524 0.762)
			(stroke
				(width 0.1524)
				(type default)
			)
			(layer "F.SilkS")
		)
		(fp_line
			(start -1.524 0.762)
			(end -1.524 -0.762)
			(stroke
				(width 0.1524)
				(type default)
			)
			(layer "F.SilkS")
		)
		(fp_line
			(start 1.1049 -0.724916)
			(end -1.1049 -0.724916)
			(stroke
				(width 0.1)
				(type default)
			)
			(layer "F.Fab")
		)
		(fp_line
			(start -1.1049 -0.724916)
			(end -1.1049 0.724916)
			(stroke
				(width 0.1)
				(type default)
			)
			(layer "F.Fab")
		)
		(fp_line
			(start 1.1049 0.724916)
			(end 1.1049 -0.724916)
			(stroke
				(width 0.1)
				(type default)
			)
			(layer "F.Fab")
		)
		(fp_line
			(start -1.1049 0.724916)
			(end 1.1049 0.724916)
			(stroke
				(width 0.1)
				(type default)
			)
			(layer "F.Fab")
		)
		(pad "1" smd rect
			(at -0.889 0 270)
			(size 1.016 1.27)
			(layers "F.Cu" "F.Mask" "F.Paste")
			(net "P0V9_CPU0_RT_2D")
		)
		(pad "2" smd rect
			(at 0.889 0 270)
			(size 1.016 1.27)
			(layers "F.Cu" "F.Mask" "F.Paste")
			(net "GND")
		)
	)
	(footprint ""
		(layer "F.Cu")
		(at 495.525044 -306.87518 -90)
		(property "Reference" "X9003"
			(at -1.82372 4.797298 0)
			(unlocked yes)
			(layer "F.SilkS")
			(effects
				(font
					(size 0.7874 0.5842)
					(thickness 0.1524)
				)
				(justify left)
			)
		)
		(property "Value" ""
			(at 0 0 270)
			(layer "F.Fab")
			(effects
				(font
					(size 1.27 1.27)
				)
			)
		)
		(property "User Part Number" "N_A"
			(at 1.30175 1.27 0)
			(unlocked yes)
			(layer "Cmts.User")
			(hide yes)
			(effects
				(font
					(size 0.635 0.4064)
					(thickness 0.1524)
				)
			)
		)
		(property "Device Type" "TP_TDR_4P_FTS_TH-TP_TDR_4P_DIP,EMPTY,TP15"
			(at 1.30175 1.27 0)
			(unlocked yes)
			(layer "F.Fab")
			(hide yes)
			(effects
				(font
					(size 0.635 0.4064)
					(thickness 0.1524)
				)
			)
		)
		(duplicate_pad_numbers_are_jumpers no)
		(fp_line
			(start 0 3.81)
			(end 2.54 3.81)
			(stroke
				(width 0.1524)
				(type default)
			)
			(layer "F.SilkS")
		)
		(fp_line
			(start 2.54 3.81)
			(end 2.54 3.6703)
			(stroke
				(width 0.1524)
				(type default)
			)
			(layer "F.SilkS")
		)
		(fp_line
			(start 0 3.175)
			(end 0 3.81)
			(stroke
				(width 0.1524)
				(type default)
			)
			(layer "F.SilkS")
		)
		(fp_line
			(start 2.54 1.4097)
			(end 2.54 1.1303)
			(stroke
				(width 0.1524)
				(type default)
			)
			(layer "F.SilkS")
		)
		(fp_line
			(start 0 0.635)
			(end 0 1.905)
			(stroke
				(width 0.1524)
				(type default)
			)
			(layer "F.SilkS")
		)
		(fp_line
			(start 2.54 -1.1303)
			(end 2.54 -1.27)
			(stroke
				(width 0.1524)
				(type default)
			)
			(layer "F.SilkS")
		)
		(fp_line
			(start 0 -1.27)
			(end 0 -0.635)
			(stroke
				(width 0.1524)
				(type default)
			)
			(layer "F.SilkS")
		)
		(fp_line
			(start 2.54 -1.27)
			(end 0 -1.27)
			(stroke
				(width 0.1524)
				(type default)
			)
			(layer "F.SilkS")
		)
		(fp_poly
			(pts
				(xy -2.285746 -0.762) (xy -0.761746 0) (xy -2.285746 0.762)
			)
			(stroke
				(width 0)
				(type default)
			)
			(fill yes)
			(layer "F.SilkS")
		)
		(fp_line
			(start 0 3.81)
			(end 2.54 3.81)
			(stroke
				(width 0.1)
				(type default)
			)
			(layer "F.Fab")
		)
		(fp_line
			(start 2.54 3.81)
			(end 2.54 -1.27)
			(stroke
				(width 0.1)
				(type default)
			)
			(layer "F.Fab")
		)
		(fp_line
			(start 0 -1.27)
			(end 0 3.81)
			(stroke
				(width 0.1)
				(type default)
			)
			(layer "F.Fab")
		)
		(fp_line
			(start 2.54 -1.27)
			(end 0 -1.27)
			(stroke
				(width 0.1)
				(type default)
			)
			(layer "F.Fab")
		)
		(fp_poly
			(pts
				(xy -0.761746 0) (xy -2.285746 -0.762) (xy -2.285746 0.762)
			)
			(stroke
				(width 0)
				(type default)
			)
			(fill yes)
			(layer "F.Fab")
		)
		(pad "1" thru_hole circle
			(at 0 0 270)
			(size 1.0033 1.0033)
			(drill 0.249936)
			(layers "*.Cu" "*.Mask")
			(remove_unused_layers no)
			(net "TDR_DIFF_85_NECK_IN2_DP")
			(clearance 0.10795)
			(thermal_gap 0.10795)
			(padstack
				(mode front_inner_back)
				(layer "Inner"
					(shape circle)
					(size 0.8001 0.8001)
					(clearance 0.1524)
				)
				(layer "B.Cu"
					(shape circle)
					(size 1.0033 1.0033)
					(clearance 0.10795)
				)
			)
		)
		(pad "2" thru_hole circle
			(at 2.54 0 270)
			(size 1.9939 1.9939)
			(drill 0.249936)
			(layers "*.Cu" "*.Mask")
			(remove_unused_layers no)
			(net "T1_GND")
			(clearance 0.10795)
			(thermal_gap 0.10795)
			(padstack
				(mode front_inner_back)
				(layer "Inner"
					(shape circle)
					(size 0.8001 0.8001)
					(clearance 0.1524)
				)
				(layer "B.Cu"
					(shape circle)
					(size 1.9939 1.9939)
					(clearance 0.10795)
				)
			)
		)
		(pad "3" thru_hole circle
			(at 2.54 2.54 270)
			(size 1.9939 1.9939)
			(drill 0.249936)
			(layers "*.Cu" "*.Mask")
			(remove_unused_layers no)
			(net "T1_GND")
			(clearance 0.10795)
			(thermal_gap 0.10795)
			(padstack
				(mode front_inner_back)
				(layer "Inner"
					(shape circle)
					(size 0.8001 0.8001)
					(clearance 0.1524)
				)
				(layer "B.Cu"
					(shape circle)
					(size 1.9939 1.9939)
					(clearance 0.10795)
				)
			)
		)
		(pad "4" thru_hole circle
			(at 0 2.54 270)
			(size 1.0033 1.0033)
			(drill 0.249936)
			(layers "*.Cu" "*.Mask")
			(remove_unused_layers no)
			(net "TDR_DIFF_85_NECK_IN2_DN")
			(clearance 0.10795)
			(thermal_gap 0.10795)
			(padstack
				(mode front_inner_back)
				(layer "Inner"
					(shape circle)
					(size 0.8001 0.8001)
					(clearance 0.1524)
				)
				(layer "B.Cu"
					(shape circle)
					(size 1.0033 1.0033)
					(clearance 0.10795)
				)
			)
		)
	)
	(footprint ""
		(layer "F.Cu")
		(at 236.7661 -403.919182 180)
		(property "Reference" "PR3984"
			(at 0 0 180)
			(layer "F.SilkS")
			(hide yes)
			(effects
				(font
					(size 1.27 1.27)
				)
			)
		)
		(property "Value" ""
			(at 0 0 180)
			(layer "F.Fab")
			(effects
				(font
					(size 1.27 1.27)
				)
			)
		)
		(duplicate_pad_numbers_are_jumpers no)
		(fp_line
			(start 0.7874 0.4064)
			(end -0.7874 0.4064)
			(stroke
				(width 0.1524)
				(type default)
			)
			(layer "F.SilkS")
		)
		(fp_line
			(start 0.7874 -0.4064)
			(end 0.7874 0.4064)
			(stroke
				(width 0.1524)
				(type default)
			)
			(layer "F.SilkS")
		)
		(fp_line
			(start -0.7874 0.4064)
			(end -0.7874 -0.4064)
			(stroke
				(width 0.1524)
				(type default)
			)
			(layer "F.SilkS")
		)
		(fp_line
			(start -0.7874 -0.4064)
			(end 0.7874 -0.4064)
			(stroke
				(width 0.1524)
				(type default)
			)
			(layer "F.SilkS")
		)
		(fp_line
			(start 0.67945 0.3048)
			(end 0.120396 0.3048)
			(stroke
				(width 0.1)
				(type default)
			)
			(layer "F.Fab")
		)
		(fp_line
			(start 0.67945 -0.3048)
			(end 0.67945 0.3048)
			(stroke
				(width 0.1)
				(type default)
			)
			(layer "F.Fab")
		)
		(fp_line
			(start 0.12065 -0.2794)
			(end 0.12065 -0.3048)
			(stroke
				(width 0.1)
				(type default)
			)
			(layer "F.Fab")
		)
		(fp_line
			(start 0.12065 -0.3048)
			(end 0.67945 -0.3048)
			(stroke
				(width 0.1)
				(type default)
			)
			(layer "F.Fab")
		)
		(fp_line
			(start 0.120396 0.3048)
			(end 0.120396 0.2794)
			(stroke
				(width 0.1)
				(type default)
			)
			(layer "F.Fab")
		)
		(fp_line
			(start 0.120396 0.2794)
			(end -0.12065 0.2794)
			(stroke
				(width 0.1)
				(type default)
			)
			(layer "F.Fab")
		)
		(fp_line
			(start -0.12065 0.3048)
			(end -0.67945 0.3048)
			(stroke
				(width 0.1)
				(type default)
			)
			(layer "F.Fab")
		)
		(fp_line
			(start -0.12065 0.2794)
			(end -0.12065 0.3048)
			(stroke
				(width 0.1)
				(type default)
			)
			(layer "F.Fab")
		)
		(fp_line
			(start -0.12065 -0.2794)
			(end 0.12065 -0.2794)
			(stroke
				(width 0.1)
				(type default)
			)
			(layer "F.Fab")
		)
		(fp_line
			(start -0.12065 -0.305054)
			(end -0.12065 -0.2794)
			(stroke
				(width 0.1)
				(type default)
			)
			(layer "F.Fab")
		)
		(fp_line
			(start -0.67945 0.3048)
			(end -0.67945 -0.305054)
			(stroke
				(width 0.1)
				(type default)
			)
			(layer "F.Fab")
		)
		(fp_line
			(start -0.67945 -0.305054)
			(end -0.12065 -0.305054)
			(stroke
				(width 0.1)
				(type default)
			)
			(layer "F.Fab")
		)
		(pad "1" smd circle
			(at -0.40005 0 180)
			(size 0 0)
			(layers "F.Cu" "F.Mask" "F.Paste")
			(net "AGND_HSC")
		)
		(pad "2" smd circle
			(at 0.40005 0 180)
			(size 0 0)
			(layers "F.Cu" "F.Mask" "F.Paste")
			(net "HSC_MODE_4")
		)
	)
)
